#ISCELL
  logical_power design_note *
  *
#ISCELL
  mstr_misc dns *
  *
#ISCELL
  pure_quanta quanta_title_block_c *
  *
#CELL
  pure_quanta q_res *
  page184_i1
#ISCELL
  logical_power universal_gnd *
  page184_i10
#CELL
  pure_quanta q_res *
  page184_i11
#CELL
  pure_quanta q_res *
  page184_i12
#CELL
  pure_quanta q_res *
  page184_i13
#ISCELL
  logical_power universal_power *
  page184_i14
#ISCELL
  logical_power universal_gnd *
  page184_i15
#CELL
  pure_quanta q_res *
  page184_i16
#ISCELL
  logical_power universal_gnd *
  page184_i17
#CELL
  pure_quanta q_res *
  page184_i18
#ISCELL
  logical_power universal_gnd *
  page184_i19
#ISCELL
  logical_power universal_gnd *
  page184_i2
#CELL
  pure_quanta q_res *
  page184_i20
#ISCELL
  standard offpage *
  page184_i21
#CELL
  pure_quanta q_res *
  page184_i22
#CELL
  pure_quanta q_res *
  page184_i23
#CELL
  pure_quanta q_res *
  page184_i24
#ISCELL
  logical_power universal_gnd *
  page184_i25
#CELL
  pure_quanta q_res *
  page184_i26
#ISCELL
  logical_power universal_gnd *
  page184_i27
#CELL
  pure_quanta q_res *
  page184_i28
#ISCELL
  logical_power universal_gnd *
  page184_i29
#ISCELL
  logical_power universal_gnd *
  page184_i3
#CELL
  pure_quanta q_res *
  page184_i30
#ISCELL
  standard offpage *
  page184_i31
#ISCELL
  standard offpage *
  page184_i32
#ISCELL
  standard offpage *
  page184_i33
#ISCELL
  standard offpage *
  page184_i34
#CELL
  pure_quanta q_res *
  page184_i4
#CELL
  pure_quanta q_res *
  page184_i48
#CELL
  pure_quanta q_res *
  page184_i49
#CELL
  pure_quanta q_res *
  page184_i5
#CELL
  pure_quanta q_res *
  page184_i50
#ISCELL
  standard offpage *
  page184_i51
#ISCELL
  standard offpage *
  page184_i52
#ISCELL
  standard offpage *
  page184_i53
#ISCELL
  standard offpage *
  page184_i54
#ISCELL
  standard offpage *
  page184_i55
#ISCELL
  logical_power universal_gnd *
  page184_i56
#ISCELL
  logical_power universal_gnd *
  page184_i57
#CELL
  pure_quanta q_res *
  page184_i58
#CELL
  pure_quanta q_res *
  page184_i59
#CELL
  pure_quanta q_res *
  page184_i6
#ISCELL
  logical_power universal_gnd *
  page184_i60
#CELL
  pure_quanta q_res *
  page184_i61
#CELL
  pure_quanta q_res *
  page184_i62
#CELL
  pure_quanta q_res *
  page184_i63
#ISCELL
  logical_power universal_power *
  page184_i64
#ISCELL
  logical_power universal_gnd *
  page184_i65
#ISCELL
  logical_power universal_gnd *
  page184_i66
#CELL
  pure_quanta q_res *
  page184_i67
#ISCELL
  logical_power universal_gnd *
  page184_i68
#CELL
  pure_quanta q_res *
  page184_i69
#ISCELL
  logical_power universal_power *
  page184_i7
#CELL
  pure_quanta q_res *
  page184_i70
#CELL
  pure_quanta q_res *
  page184_i71
#CELL
  pure_quanta q_res *
  page184_i72
#ISCELL
  logical_power universal_power *
  page184_i73
#CELL
  pure_quanta q_res *
  page184_i74
#CELL
  pure_quanta q_res *
  page184_i75
#ISCELL
  standard offpage *
  page184_i76
#ISCELL
  standard offpage *
  page184_i77
#ISCELL
  standard offpage *
  page184_i78
#ISCELL
  standard offpage *
  page184_i79
#ISCELL
  logical_power universal_gnd *
  page184_i8
#ISCELL
  standard offpage *
  page184_i80
#ISCELL
  standard offpage *
  page184_i81
#CELL
  pure_quanta q_res *
  page184_i9
